(kicad_pcb
	(version 20260206)
	(generator "pcbnew")
	(generator_version "10.0")
	(general
		(thickness 1.6)
		(legacy_teardrops no)
	)
	(paper "A4")
	(title_block
		(title "12092022_DA0F0TMDCD0_F0T_Management_Board_D_brd_V3_OCP.brd")
		(comment 1 "Grand Teton / footprints 768-773 of 1440")
	)
	(layers
		(0 "F.Cu" signal "TOP")
		(4 "In1.Cu" signal "GND")
		(6 "In2.Cu" signal "IN1")
		(8 "In3.Cu" signal "GND1")
		(10 "In4.Cu" signal "IN2")
		(12 "In5.Cu" signal "VCC")
		(14 "In6.Cu" signal "VCC1")
		(16 "In7.Cu" signal "IN3")
		(18 "In8.Cu" signal "GND2")
		(20 "In9.Cu" signal "IN4")
		(22 "In10.Cu" signal "GND3")
		(2 "B.Cu" signal "BOTTOM")
		(9 "F.Adhes" user "F.Adhesive")
		(11 "B.Adhes" user "B.Adhesive")
		(13 "F.Paste" user "Package Geometry/Pastemask Top")
		(15 "B.Paste" user "Package Geometry/Pastemask Bottom")
		(5 "F.SilkS" user "Ref Des/Silkscreen Top")
		(7 "B.SilkS" user "Ref Des/Silkscreen Bottom")
		(1 "F.Mask" user "Board Geometry/Soldermask Top")
		(3 "B.Mask" user "Board Geometry/Soldermask Bottom")
		(17 "Dwgs.User" user "User.Drawings")
		(19 "Cmts.User" user "User.Comments")
		(21 "Eco1.User" user "User.Eco1")
		(23 "Eco2.User" user "User.Eco2")
		(25 "Edge.Cuts" user "Board Geometry/Outline")
		(27 "Margin" user)
		(31 "F.CrtYd" user "Package Geometry/Place Bound Top")
		(29 "B.CrtYd" user "Package Geometry/Place Bound Bottom")
		(35 "F.Fab" user "Ref Des/Assembly Top")
		(33 "B.Fab" user "Ref Des/Assembly Bottom")
	)
	(footprint ""
		(layer "B.Cu")
		(at 60.556902 -61.858906 -90)
		(property "Reference" "R130"
			(at 0 0 90)
			(layer "B.SilkS")
			(hide yes)
			(effects
				(font
					(size 1.27 1.27)
				)
				(justify mirror)
			)
		)
		(property "Value" ""
			(at 0 0 90)
			(layer "B.Fab")
			(effects
				(font
					(size 1.27 1.27)
				)
				(justify mirror)
			)
		)
		(duplicate_pad_numbers_are_jumpers no)
		(fp_line
			(start -0.7874 0.4064)
			(end 0.7874 0.4064)
			(stroke
				(width 0.1524)
				(type default)
			)
			(layer "B.SilkS")
		)
		(fp_line
			(start 0.7874 0.4064)
			(end 0.7874 -0.4064)
			(stroke
				(width 0.1524)
				(type default)
			)
			(layer "B.SilkS")
		)
		(fp_line
			(start -0.7874 -0.4064)
			(end -0.7874 0.4064)
			(stroke
				(width 0.1524)
				(type default)
			)
			(layer "B.SilkS")
		)
		(fp_line
			(start 0.7874 -0.4064)
			(end -0.7874 -0.4064)
			(stroke
				(width 0.1524)
				(type default)
			)
			(layer "B.SilkS")
		)
		(fp_line
			(start -0.67945 0.3048)
			(end -0.120396 0.3048)
			(stroke
				(width 0.1)
				(type default)
			)
			(layer "B.Fab")
		)
		(fp_line
			(start -0.120396 0.3048)
			(end -0.120396 0.2794)
			(stroke
				(width 0.1)
				(type default)
			)
			(layer "B.Fab")
		)
		(fp_line
			(start 0.12065 0.3048)
			(end 0.67945 0.3048)
			(stroke
				(width 0.1)
				(type default)
			)
			(layer "B.Fab")
		)
		(fp_line
			(start 0.67945 0.3048)
			(end 0.67945 -0.305054)
			(stroke
				(width 0.1)
				(type default)
			)
			(layer "B.Fab")
		)
		(fp_line
			(start -0.120396 0.2794)
			(end 0.12065 0.2794)
			(stroke
				(width 0.1)
				(type default)
			)
			(layer "B.Fab")
		)
		(fp_line
			(start 0.12065 0.2794)
			(end 0.12065 0.3048)
			(stroke
				(width 0.1)
				(type default)
			)
			(layer "B.Fab")
		)
		(fp_line
			(start -0.12065 -0.2794)
			(end -0.12065 -0.3048)
			(stroke
				(width 0.1)
				(type default)
			)
			(layer "B.Fab")
		)
		(fp_line
			(start 0.12065 -0.2794)
			(end -0.12065 -0.2794)
			(stroke
				(width 0.1)
				(type default)
			)
			(layer "B.Fab")
		)
		(fp_line
			(start -0.67945 -0.3048)
			(end -0.67945 0.3048)
			(stroke
				(width 0.1)
				(type default)
			)
			(layer "B.Fab")
		)
		(fp_line
			(start -0.12065 -0.3048)
			(end -0.67945 -0.3048)
			(stroke
				(width 0.1)
				(type default)
			)
			(layer "B.Fab")
		)
		(fp_line
			(start 0.12065 -0.305054)
			(end 0.12065 -0.2794)
			(stroke
				(width 0.1)
				(type default)
			)
			(layer "B.Fab")
		)
		(fp_line
			(start 0.67945 -0.305054)
			(end 0.12065 -0.305054)
			(stroke
				(width 0.1)
				(type default)
			)
			(layer "B.Fab")
		)
		(pad "1" smd circle
			(at 0.40005 0 90)
			(size 0 0)
			(layers "B.Cu" "B.Mask" "B.Paste")
			(net "ESPI_LPC_D2_IO2")
		)
		(pad "2" smd circle
			(at -0.40005 0 90)
			(size 0 0)
			(layers "B.Cu" "B.Mask" "B.Paste")
			(net "ESPI_LPC_LAD2_IO2")
		)
	)
	(footprint ""
		(layer "B.Cu")
		(at 72.621394 -69.576188 -90)
		(property "Reference" "R686"
			(at 0 0 90)
			(layer "B.SilkS")
			(hide yes)
			(effects
				(font
					(size 1.27 1.27)
				)
				(justify mirror)
			)
		)
		(property "Value" ""
			(at 0 0 90)
			(layer "B.Fab")
			(effects
				(font
					(size 1.27 1.27)
				)
				(justify mirror)
			)
		)
		(duplicate_pad_numbers_are_jumpers no)
		(fp_line
			(start -0.7874 0.4064)
			(end 0.7874 0.4064)
			(stroke
				(width 0.1524)
				(type default)
			)
			(layer "B.SilkS")
		)
		(fp_line
			(start 0.7874 0.4064)
			(end 0.7874 -0.4064)
			(stroke
				(width 0.1524)
				(type default)
			)
			(layer "B.SilkS")
		)
		(fp_line
			(start -0.7874 -0.4064)
			(end -0.7874 0.4064)
			(stroke
				(width 0.1524)
				(type default)
			)
			(layer "B.SilkS")
		)
		(fp_line
			(start 0.7874 -0.4064)
			(end -0.7874 -0.4064)
			(stroke
				(width 0.1524)
				(type default)
			)
			(layer "B.SilkS")
		)
		(fp_line
			(start -0.67945 0.3048)
			(end -0.120396 0.3048)
			(stroke
				(width 0.1)
				(type default)
			)
			(layer "B.Fab")
		)
		(fp_line
			(start -0.120396 0.3048)
			(end -0.120396 0.2794)
			(stroke
				(width 0.1)
				(type default)
			)
			(layer "B.Fab")
		)
		(fp_line
			(start 0.12065 0.3048)
			(end 0.67945 0.3048)
			(stroke
				(width 0.1)
				(type default)
			)
			(layer "B.Fab")
		)
		(fp_line
			(start 0.67945 0.3048)
			(end 0.67945 -0.305054)
			(stroke
				(width 0.1)
				(type default)
			)
			(layer "B.Fab")
		)
		(fp_line
			(start -0.120396 0.2794)
			(end 0.12065 0.2794)
			(stroke
				(width 0.1)
				(type default)
			)
			(layer "B.Fab")
		)
		(fp_line
			(start 0.12065 0.2794)
			(end 0.12065 0.3048)
			(stroke
				(width 0.1)
				(type default)
			)
			(layer "B.Fab")
		)
		(fp_line
			(start -0.12065 -0.2794)
			(end -0.12065 -0.3048)
			(stroke
				(width 0.1)
				(type default)
			)
			(layer "B.Fab")
		)
		(fp_line
			(start 0.12065 -0.2794)
			(end -0.12065 -0.2794)
			(stroke
				(width 0.1)
				(type default)
			)
			(layer "B.Fab")
		)
		(fp_line
			(start -0.67945 -0.3048)
			(end -0.67945 0.3048)
			(stroke
				(width 0.1)
				(type default)
			)
			(layer "B.Fab")
		)
		(fp_line
			(start -0.12065 -0.3048)
			(end -0.67945 -0.3048)
			(stroke
				(width 0.1)
				(type default)
			)
			(layer "B.Fab")
		)
		(fp_line
			(start 0.12065 -0.305054)
			(end 0.12065 -0.2794)
			(stroke
				(width 0.1)
				(type default)
			)
			(layer "B.Fab")
		)
		(fp_line
			(start 0.67945 -0.305054)
			(end 0.12065 -0.305054)
			(stroke
				(width 0.1)
				(type default)
			)
			(layer "B.Fab")
		)
		(pad "1" smd circle
			(at 0.40005 0 90)
			(size 0 0)
			(layers "B.Cu" "B.Mask" "B.Paste")
			(net "P3V3_AUX")
		)
		(pad "2" smd circle
			(at -0.40005 0 90)
			(size 0 0)
			(layers "B.Cu" "B.Mask" "B.Paste")
			(net "BMC_EMMC_WP_N")
		)
	)
	(footprint ""
		(layer "B.Cu")
		(at 33.02 -101.854 -90)
		(property "Reference" "R282"
			(at 0 0 90)
			(layer "B.SilkS")
			(hide yes)
			(effects
				(font
					(size 1.27 1.27)
				)
				(justify mirror)
			)
		)
		(property "Value" ""
			(at 0 0 90)
			(layer "B.Fab")
			(effects
				(font
					(size 1.27 1.27)
				)
				(justify mirror)
			)
		)
		(duplicate_pad_numbers_are_jumpers no)
		(fp_line
			(start -0.7874 0.4064)
			(end 0.7874 0.4064)
			(stroke
				(width 0.1524)
				(type default)
			)
			(layer "B.SilkS")
		)
		(fp_line
			(start 0.7874 0.4064)
			(end 0.7874 -0.4064)
			(stroke
				(width 0.1524)
				(type default)
			)
			(layer "B.SilkS")
		)
		(fp_line
			(start -0.7874 -0.4064)
			(end -0.7874 0.4064)
			(stroke
				(width 0.1524)
				(type default)
			)
			(layer "B.SilkS")
		)
		(fp_line
			(start 0.7874 -0.4064)
			(end -0.7874 -0.4064)
			(stroke
				(width 0.1524)
				(type default)
			)
			(layer "B.SilkS")
		)
		(fp_line
			(start -0.67945 0.3048)
			(end -0.120396 0.3048)
			(stroke
				(width 0.1)
				(type default)
			)
			(layer "B.Fab")
		)
		(fp_line
			(start -0.120396 0.3048)
			(end -0.120396 0.2794)
			(stroke
				(width 0.1)
				(type default)
			)
			(layer "B.Fab")
		)
		(fp_line
			(start 0.12065 0.3048)
			(end 0.67945 0.3048)
			(stroke
				(width 0.1)
				(type default)
			)
			(layer "B.Fab")
		)
		(fp_line
			(start 0.67945 0.3048)
			(end 0.67945 -0.305054)
			(stroke
				(width 0.1)
				(type default)
			)
			(layer "B.Fab")
		)
		(fp_line
			(start -0.120396 0.2794)
			(end 0.12065 0.2794)
			(stroke
				(width 0.1)
				(type default)
			)
			(layer "B.Fab")
		)
		(fp_line
			(start 0.12065 0.2794)
			(end 0.12065 0.3048)
			(stroke
				(width 0.1)
				(type default)
			)
			(layer "B.Fab")
		)
		(fp_line
			(start -0.12065 -0.2794)
			(end -0.12065 -0.3048)
			(stroke
				(width 0.1)
				(type default)
			)
			(layer "B.Fab")
		)
		(fp_line
			(start 0.12065 -0.2794)
			(end -0.12065 -0.2794)
			(stroke
				(width 0.1)
				(type default)
			)
			(layer "B.Fab")
		)
		(fp_line
			(start -0.67945 -0.3048)
			(end -0.67945 0.3048)
			(stroke
				(width 0.1)
				(type default)
			)
			(layer "B.Fab")
		)
		(fp_line
			(start -0.12065 -0.3048)
			(end -0.67945 -0.3048)
			(stroke
				(width 0.1)
				(type default)
			)
			(layer "B.Fab")
		)
		(fp_line
			(start 0.12065 -0.305054)
			(end 0.12065 -0.2794)
			(stroke
				(width 0.1)
				(type default)
			)
			(layer "B.Fab")
		)
		(fp_line
			(start 0.67945 -0.305054)
			(end 0.12065 -0.305054)
			(stroke
				(width 0.1)
				(type default)
			)
			(layer "B.Fab")
		)
		(pad "1" smd circle
			(at 0.40005 0 90)
			(size 0 0)
			(layers "B.Cu" "B.Mask" "B.Paste")
			(net "RST_BMC_HW_R1")
		)
		(pad "2" smd circle
			(at -0.40005 0 90)
			(size 0 0)
			(layers "B.Cu" "B.Mask" "B.Paste")
			(net "RST_BMC_HW")
		)
	)
	(footprint ""
		(layer "B.Cu")
		(at 18.2118 -72.9234 180)
		(property "Reference" "R300"
			(at 0 0 0)
			(layer "B.SilkS")
			(hide yes)
			(effects
				(font
					(size 1.27 1.27)
				)
				(justify mirror)
			)
		)
		(property "Value" ""
			(at 0 0 0)
			(layer "B.Fab")
			(effects
				(font
					(size 1.27 1.27)
				)
				(justify mirror)
			)
		)
		(duplicate_pad_numbers_are_jumpers no)
		(fp_line
			(start 0.7874 0.4064)
			(end 0.7874 -0.4064)
			(stroke
				(width 0.1524)
				(type default)
			)
			(layer "B.SilkS")
		)
		(fp_line
			(start 0.7874 -0.4064)
			(end -0.7874 -0.4064)
			(stroke
				(width 0.1524)
				(type default)
			)
			(layer "B.SilkS")
		)
		(fp_line
			(start -0.7874 0.4064)
			(end 0.7874 0.4064)
			(stroke
				(width 0.1524)
				(type default)
			)
			(layer "B.SilkS")
		)
		(fp_line
			(start -0.7874 -0.4064)
			(end -0.7874 0.4064)
			(stroke
				(width 0.1524)
				(type default)
			)
			(layer "B.SilkS")
		)
		(fp_line
			(start 0.67945 0.3048)
			(end 0.67945 -0.305054)
			(stroke
				(width 0.1)
				(type default)
			)
			(layer "B.Fab")
		)
		(fp_line
			(start 0.67945 -0.305054)
			(end 0.12065 -0.305054)
			(stroke
				(width 0.1)
				(type default)
			)
			(layer "B.Fab")
		)
		(fp_line
			(start 0.12065 0.3048)
			(end 0.67945 0.3048)
			(stroke
				(width 0.1)
				(type default)
			)
			(layer "B.Fab")
		)
		(fp_line
			(start 0.12065 0.2794)
			(end 0.12065 0.3048)
			(stroke
				(width 0.1)
				(type default)
			)
			(layer "B.Fab")
		)
		(fp_line
			(start 0.12065 -0.2794)
			(end -0.12065 -0.2794)
			(stroke
				(width 0.1)
				(type default)
			)
			(layer "B.Fab")
		)
		(fp_line
			(start 0.12065 -0.305054)
			(end 0.12065 -0.2794)
			(stroke
				(width 0.1)
				(type default)
			)
			(layer "B.Fab")
		)
		(fp_line
			(start -0.120396 0.3048)
			(end -0.120396 0.2794)
			(stroke
				(width 0.1)
				(type default)
			)
			(layer "B.Fab")
		)
		(fp_line
			(start -0.120396 0.2794)
			(end 0.12065 0.2794)
			(stroke
				(width 0.1)
				(type default)
			)
			(layer "B.Fab")
		)
		(fp_line
			(start -0.12065 -0.2794)
			(end -0.12065 -0.3048)
			(stroke
				(width 0.1)
				(type default)
			)
			(layer "B.Fab")
		)
		(fp_line
			(start -0.12065 -0.3048)
			(end -0.67945 -0.3048)
			(stroke
				(width 0.1)
				(type default)
			)
			(layer "B.Fab")
		)
		(fp_line
			(start -0.67945 0.3048)
			(end -0.120396 0.3048)
			(stroke
				(width 0.1)
				(type default)
			)
			(layer "B.Fab")
		)
		(fp_line
			(start -0.67945 -0.3048)
			(end -0.67945 0.3048)
			(stroke
				(width 0.1)
				(type default)
			)
			(layer "B.Fab")
		)
		(pad "1" smd circle
			(at 0.40005 0)
			(size 0 0)
			(layers "B.Cu" "B.Mask" "B.Paste")
			(net "SMB_DEBUG_AUX_LVC3_USB_R1_SCL")
		)
		(pad "2" smd circle
			(at -0.40005 0)
			(size 0 0)
			(layers "B.Cu" "B.Mask" "B.Paste")
			(net "SMB_DEBUG_AUX_LVC3_USB_SCL")
		)
	)
	(footprint ""
		(layer "B.Cu")
		(at 68.58 -12.446 180)
		(property "Reference" "C335"
			(at 0 0 0)
			(layer "B.SilkS")
			(hide yes)
			(effects
				(font
					(size 1.27 1.27)
				)
				(justify mirror)
			)
		)
		(property "Value" ""
			(at 0 0 0)
			(layer "B.Fab")
			(effects
				(font
					(size 1.27 1.27)
				)
				(justify mirror)
			)
		)
		(duplicate_pad_numbers_are_jumpers no)
		(fp_line
			(start 0.7874 0.4064)
			(end 0.7874 -0.4064)
			(stroke
				(width 0.1524)
				(type default)
			)
			(layer "B.SilkS")
		)
		(fp_line
			(start 0.7874 -0.4064)
			(end -0.7874 -0.4064)
			(stroke
				(width 0.1524)
				(type default)
			)
			(layer "B.SilkS")
		)
		(fp_line
			(start -0.7874 0.4064)
			(end 0.7874 0.4064)
			(stroke
				(width 0.1524)
				(type default)
			)
			(layer "B.SilkS")
		)
		(fp_line
			(start -0.7874 -0.4064)
			(end -0.7874 0.4064)
			(stroke
				(width 0.1524)
				(type default)
			)
			(layer "B.SilkS")
		)
		(fp_line
			(start 0.67945 0.3048)
			(end 0.67945 -0.305054)
			(stroke
				(width 0.1)
				(type default)
			)
			(layer "B.Fab")
		)
		(fp_line
			(start 0.67945 -0.305054)
			(end 0.12065 -0.305054)
			(stroke
				(width 0.1)
				(type default)
			)
			(layer "B.Fab")
		)
		(fp_line
			(start 0.12065 0.3048)
			(end 0.67945 0.3048)
			(stroke
				(width 0.1)
				(type default)
			)
			(layer "B.Fab")
		)
		(fp_line
			(start 0.12065 0.2794)
			(end 0.12065 0.3048)
			(stroke
				(width 0.1)
				(type default)
			)
			(layer "B.Fab")
		)
		(fp_line
			(start 0.12065 -0.2794)
			(end -0.12065 -0.2794)
			(stroke
				(width 0.1)
				(type default)
			)
			(layer "B.Fab")
		)
		(fp_line
			(start 0.12065 -0.305054)
			(end 0.12065 -0.2794)
			(stroke
				(width 0.1)
				(type default)
			)
			(layer "B.Fab")
		)
		(fp_line
			(start -0.120396 0.3048)
			(end -0.120396 0.2794)
			(stroke
				(width 0.1)
				(type default)
			)
			(layer "B.Fab")
		)
		(fp_line
			(start -0.120396 0.2794)
			(end 0.12065 0.2794)
			(stroke
				(width 0.1)
				(type default)
			)
			(layer "B.Fab")
		)
		(fp_line
			(start -0.12065 -0.2794)
			(end -0.12065 -0.3048)
			(stroke
				(width 0.1)
				(type default)
			)
			(layer "B.Fab")
		)
		(fp_line
			(start -0.12065 -0.3048)
			(end -0.67945 -0.3048)
			(stroke
				(width 0.1)
				(type default)
			)
			(layer "B.Fab")
		)
		(fp_line
			(start -0.67945 0.3048)
			(end -0.120396 0.3048)
			(stroke
				(width 0.1)
				(type default)
			)
			(layer "B.Fab")
		)
		(fp_line
			(start -0.67945 -0.3048)
			(end -0.67945 0.3048)
			(stroke
				(width 0.1)
				(type default)
			)
			(layer "B.Fab")
		)
		(pad "1" smd circle
			(at 0.40005 0)
			(size 0 0)
			(layers "B.Cu" "B.Mask" "B.Paste")
			(net "REAR_AC_PWR_BMC_BTN_N")
		)
		(pad "2" smd circle
			(at -0.40005 0)
			(size 0 0)
			(layers "B.Cu" "B.Mask" "B.Paste")
			(net "GND")
		)
	)
	(footprint ""
		(layer "B.Cu")
		(at 30.5435 -41.4147 -90)
		(property "Reference" "C202"
			(at 0 0 90)
			(layer "B.SilkS")
			(hide yes)
			(effects
				(font
					(size 1.27 1.27)
				)
				(justify mirror)
			)
		)
		(property "Value" ""
			(at 0 0 90)
			(layer "B.Fab")
			(effects
				(font
					(size 1.27 1.27)
				)
				(justify mirror)
			)
		)
		(duplicate_pad_numbers_are_jumpers no)
		(fp_line
			(start -0.7874 0.4064)
			(end 0.7874 0.4064)
			(stroke
				(width 0.1524)
				(type default)
			)
			(layer "B.SilkS")
		)
		(fp_line
			(start 0.7874 0.4064)
			(end 0.7874 -0.4064)
			(stroke
				(width 0.1524)
				(type default)
			)
			(layer "B.SilkS")
		)
		(fp_line
			(start -0.7874 -0.4064)
			(end -0.7874 0.4064)
			(stroke
				(width 0.1524)
				(type default)
			)
			(layer "B.SilkS")
		)
		(fp_line
			(start 0.7874 -0.4064)
			(end -0.7874 -0.4064)
			(stroke
				(width 0.1524)
				(type default)
			)
			(layer "B.SilkS")
		)
		(fp_line
			(start -0.67945 0.3048)
			(end -0.120396 0.3048)
			(stroke
				(width 0.1)
				(type default)
			)
			(layer "B.Fab")
		)
		(fp_line
			(start -0.120396 0.3048)
			(end -0.120396 0.2794)
			(stroke
				(width 0.1)
				(type default)
			)
			(layer "B.Fab")
		)
		(fp_line
			(start 0.12065 0.3048)
			(end 0.67945 0.3048)
			(stroke
				(width 0.1)
				(type default)
			)
			(layer "B.Fab")
		)
		(fp_line
			(start 0.67945 0.3048)
			(end 0.67945 -0.305054)
			(stroke
				(width 0.1)
				(type default)
			)
			(layer "B.Fab")
		)
		(fp_line
			(start -0.120396 0.2794)
			(end 0.12065 0.2794)
			(stroke
				(width 0.1)
				(type default)
			)
			(layer "B.Fab")
		)
		(fp_line
			(start 0.12065 0.2794)
			(end 0.12065 0.3048)
			(stroke
				(width 0.1)
				(type default)
			)
			(layer "B.Fab")
		)
		(fp_line
			(start -0.12065 -0.2794)
			(end -0.12065 -0.3048)
			(stroke
				(width 0.1)
				(type default)
			)
			(layer "B.Fab")
		)
		(fp_line
			(start 0.12065 -0.2794)
			(end -0.12065 -0.2794)
			(stroke
				(width 0.1)
				(type default)
			)
			(layer "B.Fab")
		)
		(fp_line
			(start -0.67945 -0.3048)
			(end -0.67945 0.3048)
			(stroke
				(width 0.1)
				(type default)
			)
			(layer "B.Fab")
		)
		(fp_line
			(start -0.12065 -0.3048)
			(end -0.67945 -0.3048)
			(stroke
				(width 0.1)
				(type default)
			)
			(layer "B.Fab")
		)
		(fp_line
			(start 0.12065 -0.305054)
			(end 0.12065 -0.2794)
			(stroke
				(width 0.1)
				(type default)
			)
			(layer "B.Fab")
		)
		(fp_line
			(start 0.67945 -0.305054)
			(end 0.12065 -0.305054)
			(stroke
				(width 0.1)
				(type default)
			)
			(layer "B.Fab")
		)
		(pad "1" smd circle
			(at 0.40005 0 90)
			(size 0 0)
			(layers "B.Cu" "B.Mask" "B.Paste")
			(net "P5V_AUX")
		)
		(pad "2" smd circle
			(at -0.40005 0 90)
			(size 0 0)
			(layers "B.Cu" "B.Mask" "B.Paste")
			(net "GND")
		)
	)
)
